(kicad_pcb
	(version 20260206)
	(generator "pcbnew")
	(generator_version "10.0")
	(general
		(thickness 1.6)
		(legacy_teardrops no)
	)
	(paper "A4")
	(title_block
		(title "Wiwynn_Tioga_Pass_MB.brd")
		(comment 1 "Tioga Pass / footprints 4723-4730 of 4770")
	)
	(layers
		(0 "F.Cu" signal "TOP")
		(4 "In1.Cu" signal "L2GND")
		(6 "In2.Cu" signal "L3")
		(8 "In3.Cu" signal "L4GND")
		(10 "In4.Cu" signal "L5")
		(12 "In5.Cu" signal "L6GND")
		(14 "In6.Cu" signal "L7VCC")
		(16 "In7.Cu" signal "L8VCC")
		(18 "In8.Cu" signal "L9GND")
		(20 "In9.Cu" signal "L10")
		(22 "In10.Cu" signal "L11GND")
		(24 "In11.Cu" signal "L12")
		(26 "In12.Cu" signal "L13GND")
		(2 "B.Cu" signal "BOTTOM")
		(9 "F.Adhes" user "F.Adhesive")
		(11 "B.Adhes" user "B.Adhesive")
		(13 "F.Paste" user "Package Geometry/Pastemask Top")
		(15 "B.Paste" user "Package Geometry/Pastemask Bottom")
		(5 "F.SilkS" user "Ref Des/Silkscreen Top")
		(7 "B.SilkS" user "Ref Des/Silkscreen Bottom")
		(1 "F.Mask" user "Board Geometry/Soldermask Top")
		(3 "B.Mask" user "Board Geometry/Soldermask Bottom")
		(17 "Dwgs.User" user "User.Drawings")
		(19 "Cmts.User" user "User.Comments")
		(21 "Eco1.User" user "User.Eco1")
		(23 "Eco2.User" user "User.Eco2")
		(25 "Edge.Cuts" user "Board Geometry/Outline")
		(27 "Margin" user)
		(31 "F.CrtYd" user "Package Geometry/Place Bound Top")
		(29 "B.CrtYd" user "Package Geometry/Place Bound Bottom")
		(35 "F.Fab" user "Ref Des/Assembly Top")
		(33 "B.Fab" user "Ref Des/Assembly Bottom")
	)
	(footprint ""
		(layer "B.Cu")
		(at 369.443 -62.9285 180)
		(property "Reference" "R3P42"
			(at 0 0 0)
			(layer "B.SilkS")
			(hide yes)
			(effects
				(font
					(size 1.27 1.27)
				)
				(justify mirror)
			)
		)
		(property "Value" ""
			(at 0 0 0)
			(layer "B.Fab")
			(effects
				(font
					(size 1.27 1.27)
				)
				(justify mirror)
			)
		)
		(duplicate_pad_numbers_are_jumpers no)
		(fp_poly
			(pts
				(xy 0.2794 -0.1016) (xy -0.2794 -0.1016) (xy -0.2794 0.9906) (xy 0.2794 0.9906)
			)
			(stroke
				(width 0)
				(type default)
			)
			(fill no)
			(layer "B.CrtYd")
		)
		(fp_line
			(start 0.2794 0.9906)
			(end -0.2794 0.9906)
			(stroke
				(width 0.1)
				(type default)
			)
			(layer "B.Fab")
		)
		(fp_line
			(start 0.2794 -0.1016)
			(end 0.2794 0.9906)
			(stroke
				(width 0.1)
				(type default)
			)
			(layer "B.Fab")
		)
		(fp_line
			(start -0.2794 0.9906)
			(end -0.2794 -0.1016)
			(stroke
				(width 0.1)
				(type default)
			)
			(layer "B.Fab")
		)
		(fp_line
			(start -0.2794 -0.1016)
			(end 0.2794 -0.1016)
			(stroke
				(width 0.1)
				(type default)
			)
			(layer "B.Fab")
		)
		(pad "1" smd rect
			(at 0 0)
			(size 0.508 0.508)
			(layers "B.Cu" "B.Mask" "B.Paste")
			(net "FM_CPU1_THERMTRIP_LVT3_R_N")
		)
		(pad "2" smd rect
			(at 0 0.889)
			(size 0.508 0.508)
			(layers "B.Cu" "B.Mask" "B.Paste")
			(net "FM_CPU1_THERMTRIP_LVT3_N")
		)
		(zone
			(layer "B.Cu")
			(hatch none 0.5)
			(connect_pads
				(clearance 0)
			)
			(min_thickness 0.25)
			(keepout
				(tracks not_allowed)
				(vias allowed)
				(pads allowed)
				(copperpour not_allowed)
				(footprints allowed)
			)
			(placement
				(enabled no)
				(sheetname "")
			)
			(fill
				(thermal_gap 0.5)
				(thermal_bridge_width 0.5)
				(island_removal_mode 0)
			)
			(polygon
				(pts
					(xy 369.189 -63.5635) (xy 369.697 -63.5635) (xy 369.697 -63.1825) (xy 369.189 -63.1825)
				)
			)
		)
		(zone
			(layer "B.Cu")
			(hatch none 0.5)
			(connect_pads
				(clearance 0)
			)
			(min_thickness 0.25)
			(keepout
				(tracks allowed)
				(vias not_allowed)
				(pads allowed)
				(copperpour not_allowed)
				(footprints allowed)
			)
			(placement
				(enabled no)
				(sheetname "")
			)
			(fill
				(thermal_gap 0.5)
				(thermal_bridge_width 0.5)
				(island_removal_mode 0)
			)
			(polygon
				(pts
					(xy 369.189 -63.1825) (xy 369.697 -63.1825) (xy 369.697 -63.5635) (xy 369.189 -63.5635)
				)
			)
		)
	)
	(footprint ""
		(layer "B.Cu")
		(at 454.4822 -128.6764 -90)
		(property "Reference" "U1M5"
			(at 1.4986 3.64109 270)
			(unlocked yes)
			(layer "B.SilkS")
			(effects
				(font
					(size 0.7874 0.5842)
					(thickness 0.1524)
				)
				(justify left mirror)
			)
		)
		(property "Value" ""
			(at 0 0 90)
			(layer "B.Fab")
			(effects
				(font
					(size 1.27 1.27)
				)
				(justify mirror)
			)
		)
		(duplicate_pad_numbers_are_jumpers no)
		(fp_circle
			(center 0.4699 -0.8382)
			(end 0.4699 -0.9652)
			(stroke
				(width 0.254)
				(type default)
			)
			(fill no)
			(layer "B.SilkS")
		)
		(fp_poly
			(pts
				(xy -0.21463 -0.450088) (xy -1.56337 -0.450088) (xy -1.56337 1.75006) (xy -0.21463 1.75006)
			)
			(stroke
				(width 0)
				(type default)
			)
			(fill no)
			(layer "B.CrtYd")
		)
		(fp_line
			(start -1.56337 1.75006)
			(end -0.21463 1.75006)
			(stroke
				(width 0.1)
				(type default)
			)
			(layer "B.Fab")
		)
		(fp_line
			(start -0.21463 1.75006)
			(end -0.21463 -0.450088)
			(stroke
				(width 0.1)
				(type default)
			)
			(layer "B.Fab")
		)
		(fp_line
			(start -1.56337 -0.450088)
			(end -1.56337 1.75006)
			(stroke
				(width 0.1)
				(type default)
			)
			(layer "B.Fab")
		)
		(fp_line
			(start -0.21463 -0.450088)
			(end -1.56337 -0.450088)
			(stroke
				(width 0.1)
				(type default)
			)
			(layer "B.Fab")
		)
		(fp_circle
			(center 0.4699 -0.8382)
			(end 0.4699 -0.9652)
			(stroke
				(width 0.254)
				(type default)
			)
			(fill no)
			(layer "B.Fab")
		)
		(pad "1" smd rect
			(at 0 0 90)
			(size 1.016 0.381)
			(layers "B.Cu" "B.Mask" "B.Paste")
			(net "FM_CPU0_OR_CPU1_MCP_PRES")
		)
		(pad "2" smd rect
			(at 0 0.649986 90)
			(size 1.016 0.381)
			(layers "B.Cu" "B.Mask" "B.Paste")
			(net "P1V8_MCP_CPU0")
		)
		(pad "3" smd rect
			(at 0 1.299972 90)
			(size 1.016 0.381)
			(layers "B.Cu" "B.Mask" "B.Paste")
			(net "GND")
		)
		(pad "4" smd rect
			(at -1.778 1.299972 90)
			(size 1.016 0.381)
			(layers "B.Cu" "B.Mask" "B.Paste")
			(net "JTAG_MCP_TMS_R1")
		)
		(pad "5" smd rect
			(at -1.778 0 90)
			(size 1.016 0.381)
			(layers "B.Cu" "B.Mask" "B.Paste")
			(net "P3V3_STBY")
		)
	)
	(footprint ""
		(layer "B.Cu")
		(at 408.305 -150.622 90)
		(property "Reference" "C2L16"
			(at 0 0 90)
			(layer "B.SilkS")
			(hide yes)
			(effects
				(font
					(size 1.27 1.27)
				)
				(justify mirror)
			)
		)
		(property "Value" ""
			(at 0 0 90)
			(layer "B.Fab")
			(effects
				(font
					(size 1.27 1.27)
				)
				(justify mirror)
			)
		)
		(duplicate_pad_numbers_are_jumpers no)
		(fp_poly
			(pts
				(xy -0.3048 -0.1016) (xy -0.3048 0.9906) (xy 0.3048 0.9906) (xy 0.3048 -0.1016)
			)
			(stroke
				(width 0)
				(type default)
			)
			(fill no)
			(layer "B.CrtYd")
		)
		(fp_line
			(start 0.3048 -0.1016)
			(end 0.3048 0.9906)
			(stroke
				(width 0.1)
				(type default)
			)
			(layer "B.Fab")
		)
		(fp_line
			(start -0.3048 -0.1016)
			(end 0.3048 -0.1016)
			(stroke
				(width 0.1)
				(type default)
			)
			(layer "B.Fab")
		)
		(fp_line
			(start 0.3048 0.9906)
			(end -0.3048 0.9906)
			(stroke
				(width 0.1)
				(type default)
			)
			(layer "B.Fab")
		)
		(fp_line
			(start -0.3048 0.9906)
			(end -0.3048 -0.1016)
			(stroke
				(width 0.1)
				(type default)
			)
			(layer "B.Fab")
		)
		(pad "1" smd rect
			(at 0 0 270)
			(size 0.508 0.508)
			(layers "B.Cu" "B.Mask" "B.Paste")
			(net "SATA6G_PCH_PCIE_UP_SATA_RXP<6>")
		)
		(pad "2" smd rect
			(at 0 0.889 270)
			(size 0.508 0.508)
			(layers "B.Cu" "B.Mask" "B.Paste")
			(net "SATA6G_P6_RX_C_DP")
		)
		(zone
			(layer "B.Cu")
			(hatch none 0.5)
			(connect_pads
				(clearance 0)
			)
			(min_thickness 0.25)
			(keepout
				(tracks allowed)
				(vias not_allowed)
				(pads allowed)
				(copperpour not_allowed)
				(footprints allowed)
			)
			(placement
				(enabled no)
				(sheetname "")
			)
			(fill
				(thermal_gap 0.5)
				(thermal_bridge_width 0.5)
				(island_removal_mode 0)
			)
			(polygon
				(pts
					(xy 408.559 -150.876) (xy 408.559 -150.368) (xy 408.94 -150.368) (xy 408.94 -150.876)
				)
			)
		)
		(zone
			(layer "B.Cu")
			(hatch none 0.5)
			(connect_pads
				(clearance 0)
			)
			(min_thickness 0.25)
			(keepout
				(tracks not_allowed)
				(vias allowed)
				(pads allowed)
				(copperpour not_allowed)
				(footprints allowed)
			)
			(placement
				(enabled no)
				(sheetname "")
			)
			(fill
				(thermal_gap 0.5)
				(thermal_bridge_width 0.5)
				(island_removal_mode 0)
			)
			(polygon
				(pts
					(xy 408.94 -150.876) (xy 408.94 -150.368) (xy 408.559 -150.368) (xy 408.559 -150.876)
				)
			)
		)
	)
	(footprint ""
		(layer "B.Cu")
		(at 484.251 -55.6641)
		(property "Reference" "D25W8"
			(at 0 0 0)
			(layer "B.SilkS")
			(hide yes)
			(effects
				(font
					(size 1.27 1.27)
				)
				(justify mirror)
			)
		)
		(property "Value" "*"
			(at 0 -6.8961 0)
			(unlocked yes)
			(layer "B.Fab")
			(hide yes)
			(effects
				(font
					(size 1.27 1.016)
					(thickness 0.1524)
				)
				(justify mirror)
			)
		)
		(property "Device Type" "RB551V30-GP_DISCRET-G-RB551V30A"
			(at 0 -8.8011 0)
			(unlocked yes)
			(layer "B.Fab")
			(hide yes)
			(effects
				(font
					(size 1.27 1.016)
					(thickness 0.1524)
				)
				(justify mirror)
			)
		)
		(duplicate_pad_numbers_are_jumpers no)
		(fp_line
			(start -0.889 -1.9304)
			(end -0.889 2.159)
			(stroke
				(width 0.1524)
				(type default)
			)
			(layer "B.SilkS")
		)
		(fp_line
			(start -0.889 2.159)
			(end 0.889 2.159)
			(stroke
				(width 0.1524)
				(type default)
			)
			(layer "B.SilkS")
		)
		(fp_line
			(start -0.762 2.0574)
			(end 0.762 2.0574)
			(stroke
				(width 0.508)
				(type default)
			)
			(layer "B.SilkS")
		)
		(fp_line
			(start 0.889 -1.9304)
			(end -0.889 -1.9304)
			(stroke
				(width 0.1524)
				(type default)
			)
			(layer "B.SilkS")
		)
		(fp_line
			(start 0.889 2.159)
			(end 0.889 -1.9304)
			(stroke
				(width 0.1524)
				(type default)
			)
			(layer "B.SilkS")
		)
		(fp_rect
			(start 1.016 2.3114)
			(end -1.016 -2.0066)
			(stroke
				(width 0)
				(type default)
			)
			(fill no)
			(layer "B.CrtYd")
		)
		(fp_poly
			(pts
				(xy 1.016 -2.0066) (xy -1.016 -2.0066) (xy -1.016 2.3114) (xy 1.016 2.3114)
			)
			(stroke
				(width 0)
				(type default)
			)
			(fill no)
			(layer "B.Fab")
		)
		(pad "A" smd rect
			(at 0 -1.143 180)
			(size 0.5588 1.016)
			(layers "B.Cu" "B.Mask" "B.Paste")
			(net "P5V")
		)
		(pad "K" smd rect
			(at 0 1.143 180)
			(size 0.5588 1.016)
			(layers "B.Cu" "B.Mask" "B.Paste")
			(net "P5V_VGA_D")
		)
	)
	(footprint ""
		(layer "B.Cu")
		(at 272.861532 -3.3528 90)
		(property "Reference" "C5G58"
			(at -1.14681 0.76708 180)
			(unlocked yes)
			(layer "B.SilkS")
			(effects
				(font
					(size 0.7874 0.5842)
					(thickness 0.1524)
				)
				(justify mirror)
			)
		)
		(property "Value" ""
			(at 0 0 90)
			(layer "B.Fab")
			(effects
				(font
					(size 1.27 1.27)
				)
				(justify mirror)
			)
		)
		(duplicate_pad_numbers_are_jumpers no)
		(fp_rect
			(start -0.4953 -0.2032)
			(end 0.4953 1.6002)
			(stroke
				(width 0)
				(type default)
			)
			(fill no)
			(layer "B.CrtYd")
		)
		(fp_line
			(start 0.4953 -0.2032)
			(end -0.4953 -0.2032)
			(stroke
				(width 0.1)
				(type default)
			)
			(layer "B.Fab")
		)
		(fp_line
			(start -0.4953 -0.2032)
			(end -0.4953 1.6002)
			(stroke
				(width 0.1)
				(type default)
			)
			(layer "B.Fab")
		)
		(fp_line
			(start 0.4953 1.6002)
			(end 0.4953 -0.2032)
			(stroke
				(width 0.1)
				(type default)
			)
			(layer "B.Fab")
		)
		(fp_line
			(start -0.4953 1.6002)
			(end 0.4953 1.6002)
			(stroke
				(width 0.1)
				(type default)
			)
			(layer "B.Fab")
		)
		(pad "1" smd rect
			(at 0 0 270)
			(size 0.762 0.889)
			(layers "B.Cu" "B.Mask" "B.Paste")
			(net "PVDDQ_ABC")
		)
		(pad "2" smd rect
			(at 0 1.397 270)
			(size 0.762 0.889)
			(layers "B.Cu" "B.Mask" "B.Paste")
			(net "GND")
		)
		(zone
			(layer "B.Cu")
			(hatch none 0.5)
			(connect_pads
				(clearance 0)
			)
			(min_thickness 0.25)
			(keepout
				(tracks not_allowed)
				(vias allowed)
				(pads allowed)
				(copperpour not_allowed)
				(footprints allowed)
			)
			(placement
				(enabled no)
				(sheetname "")
			)
			(fill
				(thermal_gap 0.5)
				(thermal_bridge_width 0.5)
				(island_removal_mode 0)
			)
			(polygon
				(pts
					(xy 273.306032 -2.9718) (xy 273.814032 -2.9718) (xy 273.814032 -3.7338) (xy 273.306032 -3.7338)
				)
			)
		)
	)
	(footprint ""
		(layer "B.Cu")
		(at 364.381288 -48.242728 90)
		(property "Reference" "C2T33"
			(at 0 0 90)
			(layer "B.SilkS")
			(hide yes)
			(effects
				(font
					(size 1.27 1.27)
				)
				(justify mirror)
			)
		)
		(property "Value" ""
			(at 0 0 90)
			(layer "B.Fab")
			(effects
				(font
					(size 1.27 1.27)
				)
				(justify mirror)
			)
		)
		(duplicate_pad_numbers_are_jumpers no)
		(fp_poly
			(pts
				(xy -0.3048 -0.1016) (xy -0.3048 0.9906) (xy 0.3048 0.9906) (xy 0.3048 -0.1016)
			)
			(stroke
				(width 0)
				(type default)
			)
			(fill no)
			(layer "B.CrtYd")
		)
		(fp_line
			(start 0.3048 -0.1016)
			(end 0.3048 0.9906)
			(stroke
				(width 0.1)
				(type default)
			)
			(layer "B.Fab")
		)
		(fp_line
			(start -0.3048 -0.1016)
			(end 0.3048 -0.1016)
			(stroke
				(width 0.1)
				(type default)
			)
			(layer "B.Fab")
		)
		(fp_line
			(start 0.3048 0.9906)
			(end -0.3048 0.9906)
			(stroke
				(width 0.1)
				(type default)
			)
			(layer "B.Fab")
		)
		(fp_line
			(start -0.3048 0.9906)
			(end -0.3048 -0.1016)
			(stroke
				(width 0.1)
				(type default)
			)
			(layer "B.Fab")
		)
		(pad "1" smd rect
			(at 0 0 270)
			(size 0.508 0.508)
			(layers "B.Cu" "B.Mask" "B.Paste")
			(net "P3V3")
		)
		(pad "2" smd rect
			(at 0 0.889 270)
			(size 0.508 0.508)
			(layers "B.Cu" "B.Mask" "B.Paste")
			(net "GND")
		)
		(zone
			(layer "B.Cu")
			(hatch none 0.5)
			(connect_pads
				(clearance 0)
			)
			(min_thickness 0.25)
			(keepout
				(tracks allowed)
				(vias not_allowed)
				(pads allowed)
				(copperpour not_allowed)
				(footprints allowed)
			)
			(placement
				(enabled no)
				(sheetname "")
			)
			(fill
				(thermal_gap 0.5)
				(thermal_bridge_width 0.5)
				(island_removal_mode 0)
			)
			(polygon
				(pts
					(xy 364.635288 -48.496728) (xy 364.635288 -47.988728) (xy 365.016288 -47.988728) (xy 365.016288 -48.496728)
				)
			)
		)
		(zone
			(layer "B.Cu")
			(hatch none 0.5)
			(connect_pads
				(clearance 0)
			)
			(min_thickness 0.25)
			(keepout
				(tracks not_allowed)
				(vias allowed)
				(pads allowed)
				(copperpour not_allowed)
				(footprints allowed)
			)
			(placement
				(enabled no)
				(sheetname "")
			)
			(fill
				(thermal_gap 0.5)
				(thermal_bridge_width 0.5)
				(island_removal_mode 0)
			)
			(polygon
				(pts
					(xy 365.016288 -48.496728) (xy 365.016288 -47.988728) (xy 364.635288 -47.988728) (xy 364.635288 -48.496728)
				)
			)
		)
	)
	(footprint ""
		(layer "B.Cu")
		(at 471.17 -113.0554 90)
		(property "Reference" "R1M15"
			(at 0 0 90)
			(layer "B.SilkS")
			(hide yes)
			(effects
				(font
					(size 1.27 1.27)
				)
				(justify mirror)
			)
		)
		(property "Value" ""
			(at 0 0 90)
			(layer "B.Fab")
			(effects
				(font
					(size 1.27 1.27)
				)
				(justify mirror)
			)
		)
		(duplicate_pad_numbers_are_jumpers no)
		(fp_poly
			(pts
				(xy 0.2794 -0.1016) (xy -0.2794 -0.1016) (xy -0.2794 0.9906) (xy 0.2794 0.9906)
			)
			(stroke
				(width 0)
				(type default)
			)
			(fill no)
			(layer "B.CrtYd")
		)
		(fp_line
			(start 0.2794 -0.1016)
			(end 0.2794 0.9906)
			(stroke
				(width 0.1)
				(type default)
			)
			(layer "B.Fab")
		)
		(fp_line
			(start -0.2794 -0.1016)
			(end 0.2794 -0.1016)
			(stroke
				(width 0.1)
				(type default)
			)
			(layer "B.Fab")
		)
		(fp_line
			(start 0.2794 0.9906)
			(end -0.2794 0.9906)
			(stroke
				(width 0.1)
				(type default)
			)
			(layer "B.Fab")
		)
		(fp_line
			(start -0.2794 0.9906)
			(end -0.2794 -0.1016)
			(stroke
				(width 0.1)
				(type default)
			)
			(layer "B.Fab")
		)
		(pad "1" smd rect
			(at 0 0 270)
			(size 0.508 0.508)
			(layers "B.Cu" "B.Mask" "B.Paste")
			(net "RMII_BMC_OCP_CRSDV")
		)
		(pad "2" smd rect
			(at 0 0.889 270)
			(size 0.508 0.508)
			(layers "B.Cu" "B.Mask" "B.Paste")
			(net "RMII_BMC_OCP_CRSDV_R")
		)
		(zone
			(layer "B.Cu")
			(hatch none 0.5)
			(connect_pads
				(clearance 0)
			)
			(min_thickness 0.25)
			(keepout
				(tracks allowed)
				(vias not_allowed)
				(pads allowed)
				(copperpour not_allowed)
				(footprints allowed)
			)
			(placement
				(enabled no)
				(sheetname "")
			)
			(fill
				(thermal_gap 0.5)
				(thermal_bridge_width 0.5)
				(island_removal_mode 0)
			)
			(polygon
				(pts
					(xy 471.424 -113.3094) (xy 471.424 -112.8014) (xy 471.805 -112.8014) (xy 471.805 -113.3094)
				)
			)
		)
		(zone
			(layer "B.Cu")
			(hatch none 0.5)
			(connect_pads
				(clearance 0)
			)
			(min_thickness 0.25)
			(keepout
				(tracks not_allowed)
				(vias allowed)
				(pads allowed)
				(copperpour not_allowed)
				(footprints allowed)
			)
			(placement
				(enabled no)
				(sheetname "")
			)
			(fill
				(thermal_gap 0.5)
				(thermal_bridge_width 0.5)
				(island_removal_mode 0)
			)
			(polygon
				(pts
					(xy 471.805 -113.3094) (xy 471.805 -112.8014) (xy 471.424 -112.8014) (xy 471.424 -113.3094)
				)
			)
		)
	)
	(footprint ""
		(layer "B.Cu")
		(at 197.950328 -84.493862 90)
		(property "Reference" "C6P7"
			(at 0 0 90)
			(layer "B.SilkS")
			(hide yes)
			(effects
				(font
					(size 1.27 1.27)
				)
				(justify mirror)
			)
		)
		(property "Value" ""
			(at 0 0 90)
			(layer "B.Fab")
			(effects
				(font
					(size 1.27 1.27)
				)
				(justify mirror)
			)
		)
		(duplicate_pad_numbers_are_jumpers no)
		(fp_rect
			(start -0.7239 -0.2159)
			(end 0.7239 1.9939)
			(stroke
				(width 0)
				(type default)
			)
			(fill no)
			(layer "B.CrtYd")
		)
		(fp_line
			(start 0.7239 -0.2159)
			(end 0.7239 1.9939)
			(stroke
				(width 0.1)
				(type default)
			)
			(layer "B.Fab")
		)
		(fp_line
			(start -0.7239 -0.2159)
			(end 0.7239 -0.2159)
			(stroke
				(width 0.1)
				(type default)
			)
			(layer "B.Fab")
		)
		(fp_line
			(start 0.7239 1.9939)
			(end -0.7239 1.9939)
			(stroke
				(width 0.1)
				(type default)
			)
			(layer "B.Fab")
		)
		(fp_line
			(start -0.7239 1.9939)
			(end -0.7239 -0.2159)
			(stroke
				(width 0.1)
				(type default)
			)
			(layer "B.Fab")
		)
		(pad "1" smd rect
			(at 0 0 270)
			(size 1.27 1.016)
			(layers "B.Cu" "B.Mask" "B.Paste")
			(net "VR_FET_SW_P12V_STBY_PVCCIN_CPU0")
		)
		(pad "2" smd rect
			(at 0 1.778 270)
			(size 1.27 1.016)
			(layers "B.Cu" "B.Mask" "B.Paste")
			(net "GND")
		)
		(zone
			(layer "B.Cu")
			(hatch none 0.5)
			(connect_pads
				(clearance 0)
			)
			(min_thickness 0.25)
			(keepout
				(tracks not_allowed)
				(vias allowed)
				(pads allowed)
				(copperpour not_allowed)
				(footprints allowed)
			)
			(placement
				(enabled no)
				(sheetname "")
			)
			(fill
				(thermal_gap 0.5)
				(thermal_bridge_width 0.5)
				(island_removal_mode 0)
			)
			(polygon
				(pts
					(xy 198.458328 -83.858862) (xy 199.220328 -83.858862) (xy 199.220328 -85.128862) (xy 198.458328 -85.128862)
				)
			)
		)
	)
)
